(kicad_pcb
	(version 20241229)
	(generator "pcbnew")
	(generator_version "9.0")
	(general
		(thickness 1.63)
		(legacy_teardrops no)
	)
	(paper "A4")
	(title_block
		(title "CM4 Baseboard")
		(date "2026-01-05")
		(rev "1.1.1")
		(company "Antmicro Ltd")
		(comment 1 "www.antmicro.com")
		(comment 9 "footprints 117-121 of 506")
	)
	(layers
		(0 "F.Cu" signal)
		(4 "In1.Cu" power)
		(6 "In2.Cu" power)
		(8 "In3.Cu" signal)
		(10 "In4.Cu" signal)
		(2 "B.Cu" signal)
		(9 "F.Adhes" user "F.Adhesive")
		(11 "B.Adhes" user "B.Adhesive")
		(13 "F.Paste" user)
		(15 "B.Paste" user)
		(5 "F.SilkS" user "F.Silkscreen")
		(7 "B.SilkS" user "B.Silkscreen")
		(1 "F.Mask" user)
		(3 "B.Mask" user)
		(17 "Dwgs.User" user "User.Drawings")
		(19 "Cmts.User" user "User.Comments")
		(21 "Eco1.User" user "User.Eco1")
		(23 "Eco2.User" user "User.Eco2")
		(25 "Edge.Cuts" user)
		(27 "Margin" user)
		(31 "F.CrtYd" user "F.Courtyard")
		(29 "B.CrtYd" user "B.Courtyard")
		(35 "F.Fab" user)
		(33 "B.Fab" user)
	)
	(footprint "antmicro-footprints:R_0402_1005Metric"
		(layer "F.Cu")
		(at 117.88 154.3915 180)
		(descr "Resistor SMD 0402")
		(tags "resistor SMD 0402")
		(property "Reference" "R217"
			(at -3.525 -0.325 180)
			(layer "F.SilkS")
			(effects
				(font
					(size 0.7 0.7)
					(thickness 0.15)
				)
				(justify left bottom)
			)
		)
		(property "Value" "R_0R_0402"
			(at -1.011843 1.772047 180)
			(layer "F.Fab")
			(effects
				(font
					(size 0.7 0.7)
					(thickness 0.15)
				)
				(justify left bottom)
			)
		)
		(property "Datasheet" "https://industrial.panasonic.com/cdbs/www-data/pdf/RDA0000/AOA0000C301.pdf"
			(at 0 0 180)
			(layer "F.Fab")
			(hide yes)
			(effects
				(font
					(size 1.27 1.27)
					(thickness 0.15)
				)
			)
		)
		(property "Manufacturer" "Panasonic"
			(at 0 0 180)
			(unlocked yes)
			(layer "F.Fab")
			(hide yes)
			(effects
				(font
					(size 1 1)
					(thickness 0.15)
				)
			)
		)
		(property "MPN" "ERJ2GE0R00X"
			(at 0 0 180)
			(unlocked yes)
			(layer "F.Fab")
			(hide yes)
			(effects
				(font
					(size 1 1)
					(thickness 0.15)
				)
			)
		)
		(property "Val" "0R"
			(at 0 0 180)
			(unlocked yes)
			(layer "F.Fab")
			(hide yes)
			(effects
				(font
					(size 1 1)
					(thickness 0.15)
				)
			)
		)
		(property "License" "Apache-2.0"
			(at 0 0 180)
			(unlocked yes)
			(layer "F.Fab")
			(hide yes)
			(effects
				(font
					(size 1 1)
					(thickness 0.15)
				)
			)
		)
		(property "Author" "Antmicro"
			(at 0 0 180)
			(unlocked yes)
			(layer "F.Fab")
			(hide yes)
			(effects
				(font
					(size 1 1)
					(thickness 0.15)
				)
			)
		)
		(property "Tolerance" "~"
			(at 0 0 180)
			(unlocked yes)
			(layer "F.Fab")
			(hide yes)
			(effects
				(font
					(size 1 1)
					(thickness 0.15)
				)
			)
		)
		(property "Current" "1A"
			(at 0 0 180)
			(unlocked yes)
			(layer "F.Fab")
			(hide yes)
			(effects
				(font
					(size 1 1)
					(thickness 0.15)
				)
			)
		)
		(sheetname "/Compute module/")
		(sheetfile "compute-module.kicad_sch")
		(attr smd)
		(fp_rect
			(start -0.925 -0.47)
			(end 0.925 0.47)
			(stroke
				(width 0.05)
				(type default)
			)
			(fill no)
			(layer "F.CrtYd")
		)
		(fp_rect
			(start -0.5 -0.25)
			(end 0.5 0.25)
			(stroke
				(width 0.15)
				(type solid)
			)
			(fill no)
			(layer "F.Fab")
		)
		(fp_text user "${REFERENCE}"
			(at -0.95 3.168 180)
			(layer "F.Fab")
			(effects
				(font
					(size 0.7 0.7)
					(thickness 0.15)
				)
				(justify left bottom)
			)
		)
		(fp_text user "License: Apache-2.0"
			(at -0.95 5.169 180)
			(layer "F.Fab")
			(effects
				(font
					(size 0.7 0.7)
					(thickness 0.15)
				)
				(justify left bottom)
			)
		)
		(fp_text user "Author: Antmicro"
			(at -0.95 4.169 180)
			(layer "F.Fab")
			(effects
				(font
					(size 0.7 0.7)
					(thickness 0.15)
				)
				(justify left bottom)
			)
		)
		(pad "1" smd roundrect
			(at -0.48 0 180)
			(size 0.59 0.64)
			(layers "F.Cu" "F.Mask" "F.Paste")
			(roundrect_rratio 0.25)
			(net 168 "/Compute module/NVMe.TX1_N")
			(pintype "passive")
		)
		(pad "2" smd roundrect
			(at 0.48 0 180)
			(size 0.59 0.64)
			(layers "F.Cu" "F.Mask" "F.Paste")
			(roundrect_rratio 0.25)
			(net 146 "/Compute module/T1_N")
			(pintype "passive")
		)
	)
	(footprint "antmicro-footprints:R_0402_1005Metric"
		(layer "F.Cu")
		(at 140.132962 131.7365)
		(descr "Resistor SMD 0402")
		(tags "resistor SMD 0402")
		(property "Reference" "R259"
			(at -3.665 0.38 0)
			(layer "F.SilkS")
			(effects
				(font
					(size 0.7 0.7)
					(thickness 0.15)
				)
				(justify left bottom)
			)
		)
		(property "Value" "R_0R_0402"
			(at -1.011843 1.772047 0)
			(layer "F.Fab")
			(effects
				(font
					(size 0.7 0.7)
					(thickness 0.15)
				)
				(justify left bottom)
			)
		)
		(property "Datasheet" "https://industrial.panasonic.com/cdbs/www-data/pdf/RDA0000/AOA0000C301.pdf"
			(at 0 0 0)
			(layer "F.Fab")
			(hide yes)
			(effects
				(font
					(size 1.27 1.27)
					(thickness 0.15)
				)
			)
		)
		(property "Manufacturer" "Panasonic"
			(at 0 0 0)
			(unlocked yes)
			(layer "F.Fab")
			(hide yes)
			(effects
				(font
					(size 1 1)
					(thickness 0.15)
				)
			)
		)
		(property "MPN" "ERJ2GE0R00X"
			(at 0 0 0)
			(unlocked yes)
			(layer "F.Fab")
			(hide yes)
			(effects
				(font
					(size 1 1)
					(thickness 0.15)
				)
			)
		)
		(property "Val" "0R"
			(at 0 0 0)
			(unlocked yes)
			(layer "F.Fab")
			(hide yes)
			(effects
				(font
					(size 1 1)
					(thickness 0.15)
				)
			)
		)
		(property "License" "Apache-2.0"
			(at 0 0 0)
			(unlocked yes)
			(layer "F.Fab")
			(hide yes)
			(effects
				(font
					(size 1 1)
					(thickness 0.15)
				)
			)
		)
		(property "Author" "Antmicro"
			(at 0 0 0)
			(unlocked yes)
			(layer "F.Fab")
			(hide yes)
			(effects
				(font
					(size 1 1)
					(thickness 0.15)
				)
			)
		)
		(property "Tolerance" "~"
			(at 0 0 0)
			(unlocked yes)
			(layer "F.Fab")
			(hide yes)
			(effects
				(font
					(size 1 1)
					(thickness 0.15)
				)
			)
		)
		(property "Current" "1A"
			(at 0 0 0)
			(unlocked yes)
			(layer "F.Fab")
			(hide yes)
			(effects
				(font
					(size 1 1)
					(thickness 0.15)
				)
			)
		)
		(sheetname "/Compute module/")
		(sheetfile "compute-module.kicad_sch")
		(attr smd)
		(fp_rect
			(start -0.925 -0.47)
			(end 0.925 0.47)
			(stroke
				(width 0.05)
				(type default)
			)
			(fill no)
			(layer "F.CrtYd")
		)
		(fp_rect
			(start -0.5 -0.25)
			(end 0.5 0.25)
			(stroke
				(width 0.15)
				(type solid)
			)
			(fill no)
			(layer "F.Fab")
		)
		(fp_text user "License: Apache-2.0"
			(at -0.95 5.169 0)
			(layer "F.Fab")
			(effects
				(font
					(size 0.7 0.7)
					(thickness 0.15)
				)
				(justify left bottom)
			)
		)
		(fp_text user "Author: Antmicro"
			(at -0.95 4.169 0)
			(layer "F.Fab")
			(effects
				(font
					(size 0.7 0.7)
					(thickness 0.15)
				)
				(justify left bottom)
			)
		)
		(fp_text user "${REFERENCE}"
			(at -0.95 3.168 0)
			(layer "F.Fab")
			(effects
				(font
					(size 0.7 0.7)
					(thickness 0.15)
				)
				(justify left bottom)
			)
		)
		(pad "1" smd roundrect
			(at -0.48 0)
			(size 0.59 0.64)
			(layers "F.Cu" "F.Mask" "F.Paste")
			(roundrect_rratio 0.25)
			(net 446 "/Compute module/GPIO.1{slash}SCL0")
			(pintype "passive")
		)
		(pad "2" smd roundrect
			(at 0.48 0)
			(size 0.59 0.64)
			(layers "F.Cu" "F.Mask" "F.Paste")
			(roundrect_rratio 0.25)
			(net 140 "/CSI/I_{2}C_CSI0.SCL")
			(pintype "passive")
		)
	)
	(footprint "antmicro-footprints:R_0402_1005Metric"
		(layer "F.Cu")
		(at 108.1 155.8415 180)
		(descr "Resistor SMD 0402")
		(tags "resistor SMD 0402")
		(property "Reference" "R225"
			(at 1.91 -2.495 180)
			(layer "F.SilkS")
			(effects
				(font
					(size 0.7 0.7)
					(thickness 0.15)
				)
				(justify left bottom)
			)
		)
		(property "Value" "R_0R_0402"
			(at -1.011843 1.772047 180)
			(layer "F.Fab")
			(effects
				(font
					(size 0.7 0.7)
					(thickness 0.15)
				)
				(justify left bottom)
			)
		)
		(property "Datasheet" "https://industrial.panasonic.com/cdbs/www-data/pdf/RDA0000/AOA0000C301.pdf"
			(at 0 0 180)
			(layer "F.Fab")
			(hide yes)
			(effects
				(font
					(size 1.27 1.27)
					(thickness 0.15)
				)
			)
		)
		(property "Manufacturer" "Panasonic"
			(at 0 0 180)
			(unlocked yes)
			(layer "F.Fab")
			(hide yes)
			(effects
				(font
					(size 1 1)
					(thickness 0.15)
				)
			)
		)
		(property "MPN" "ERJ2GE0R00X"
			(at 0 0 180)
			(unlocked yes)
			(layer "F.Fab")
			(hide yes)
			(effects
				(font
					(size 1 1)
					(thickness 0.15)
				)
			)
		)
		(property "Val" "0R"
			(at 0 0 180)
			(unlocked yes)
			(layer "F.Fab")
			(hide yes)
			(effects
				(font
					(size 1 1)
					(thickness 0.15)
				)
			)
		)
		(property "License" "Apache-2.0"
			(at 0 0 180)
			(unlocked yes)
			(layer "F.Fab")
			(hide yes)
			(effects
				(font
					(size 1 1)
					(thickness 0.15)
				)
			)
		)
		(property "Author" "Antmicro"
			(at 0 0 180)
			(unlocked yes)
			(layer "F.Fab")
			(hide yes)
			(effects
				(font
					(size 1 1)
					(thickness 0.15)
				)
			)
		)
		(property "Tolerance" "~"
			(at 0 0 180)
			(unlocked yes)
			(layer "F.Fab")
			(hide yes)
			(effects
				(font
					(size 1 1)
					(thickness 0.15)
				)
			)
		)
		(property "Current" "1A"
			(at 0 0 180)
			(unlocked yes)
			(layer "F.Fab")
			(hide yes)
			(effects
				(font
					(size 1 1)
					(thickness 0.15)
				)
			)
		)
		(sheetname "/Compute module/")
		(sheetfile "compute-module.kicad_sch")
		(attr smd)
		(fp_rect
			(start -0.925 -0.47)
			(end 0.925 0.47)
			(stroke
				(width 0.05)
				(type default)
			)
			(fill no)
			(layer "F.CrtYd")
		)
		(fp_rect
			(start -0.5 -0.25)
			(end 0.5 0.25)
			(stroke
				(width 0.15)
				(type solid)
			)
			(fill no)
			(layer "F.Fab")
		)
		(fp_text user "License: Apache-2.0"
			(at -0.95 5.169 180)
			(layer "F.Fab")
			(effects
				(font
					(size 0.7 0.7)
					(thickness 0.15)
				)
				(justify left bottom)
			)
		)
		(fp_text user "Author: Antmicro"
			(at -0.95 4.169 180)
			(layer "F.Fab")
			(effects
				(font
					(size 0.7 0.7)
					(thickness 0.15)
				)
				(justify left bottom)
			)
		)
		(fp_text user "${REFERENCE}"
			(at -0.95 3.168 180)
			(layer "F.Fab")
			(effects
				(font
					(size 0.7 0.7)
					(thickness 0.15)
				)
				(justify left bottom)
			)
		)
		(pad "1" smd roundrect
			(at -0.48 0 180)
			(size 0.59 0.64)
			(layers "F.Cu" "F.Mask" "F.Paste")
			(roundrect_rratio 0.25)
			(net 149 "/Compute module/R2_N")
			(pintype "passive")
		)
		(pad "2" smd roundrect
			(at 0.48 0 180)
			(size 0.59 0.64)
			(layers "F.Cu" "F.Mask" "F.Paste")
			(roundrect_rratio 0.25)
			(net 162 "/Compute module/NVMe.RX2_N")
			(pintype "passive")
		)
	)
	(footprint "antmicro-footprints:UQFN-12_2x1.7mm_P0.4mm_Texas_RUT"
		(layer "F.Cu")
		(at 85.517962 146.6165 -90)
		(descr "Texas_R_PUQFN-N12")
		(tags "Texas_R_PUQFN-N12")
		(property "Reference" "U907"
			(at -0.85 0.6 180)
			(layer "F.SilkS")
			(effects
				(font
					(size 0.7 0.7)
					(thickness 0.15)
				)
				(justify right bottom)
			)
		)
		(property "Value" "TXB0104_UQFN"
			(at 0 2.35 90)
			(layer "F.Fab")
			(effects
				(font
					(size 0.7 0.7)
					(thickness 0.15)
				)
				(justify right bottom)
			)
		)
		(property "Datasheet" "http://www.ti.com/lit/ds/symlink/txb0104.pdf"
			(at 0 0 270)
			(layer "F.Fab")
			(hide yes)
			(effects
				(font
					(size 1.27 1.27)
					(thickness 0.15)
				)
			)
		)
		(property "Manufacturer" "Texas Instruments"
			(at 0 0 270)
			(unlocked yes)
			(layer "F.Fab")
			(hide yes)
			(effects
				(font
					(size 1 1)
					(thickness 0.15)
				)
			)
		)
		(property "MPN" "TXB0104RUTR"
			(at 0 0 270)
			(unlocked yes)
			(layer "F.Fab")
			(hide yes)
			(effects
				(font
					(size 1 1)
					(thickness 0.15)
				)
			)
		)
		(property "Author" "Antmicro"
			(at 0 0 270)
			(unlocked yes)
			(layer "F.Fab")
			(hide yes)
			(effects
				(font
					(size 1 1)
					(thickness 0.15)
				)
			)
		)
		(property "License" "Apache-2.0"
			(at 0 0 270)
			(unlocked yes)
			(layer "F.Fab")
			(hide yes)
			(effects
				(font
					(size 1 1)
					(thickness 0.15)
				)
			)
		)
		(property ki_fp_filters "Texas*R*PUQFN*N12*")
		(sheetname "/USB/")
		(sheetfile "usb.kicad_sch")
		(attr smd)
		(fp_line
			(start 0.497 1.3)
			(end -0.5 1.3)
			(stroke
				(width 0.15)
				(type solid)
			)
			(layer "F.SilkS")
		)
		(fp_line
			(start 0.597 -1.301)
			(end -0.55 -1.301)
			(stroke
				(width 0.15)
				(type solid)
			)
			(layer "F.SilkS")
		)
		(fp_circle
			(center -0.85 -1.2)
			(end -0.8 -1.2)
			(stroke
				(width 0.15)
				(type solid)
			)
			(fill yes)
			(layer "F.SilkS")
		)
		(fp_rect
			(start -1.1 -1.3)
			(end 1.1 1.3)
			(stroke
				(width 0.05)
				(type solid)
			)
			(fill no)
			(layer "F.CrtYd")
		)
		(fp_line
			(start -0.85 0.997)
			(end -0.85 -0.5)
			(stroke
				(width 0.15)
				(type solid)
			)
			(layer "F.Fab")
		)
		(fp_line
			(start 0.847 0.997)
			(end -0.85 0.997)
			(stroke
				(width 0.15)
				(type solid)
			)
			(layer "F.Fab")
		)
		(fp_line
			(start -0.5 -1)
			(end -0.85 -0.5)
			(stroke
				(width 0.15)
				(type solid)
			)
			(layer "F.Fab")
		)
		(fp_line
			(start -0.5 -1)
			(end 0.847 -1)
			(stroke
				(width 0.15)
				(type solid)
			)
			(layer "F.Fab")
		)
		(fp_line
			(start 0.847 -1)
			(end 0.847 0.997)
			(stroke
				(width 0.15)
				(type solid)
			)
			(layer "F.Fab")
		)
		(fp_text user "License: Apache-2.0"
			(at -1.1 6.75 270)
			(layer "F.Fab")
			(effects
				(font
					(size 0.7 0.7)
					(thickness 0.15)
				)
				(justify left bottom)
			)
		)
		(fp_text user "Author: Antmicro"
			(at -1.1 4.35 270)
			(layer "F.Fab")
			(effects
				(font
					(size 0.7 0.7)
					(thickness 0.15)
				)
				(justify left bottom)
			)
		)
		(fp_text user "${REFERENCE}"
			(at -1.1 5.55 270)
			(layer "F.Fab")
			(effects
				(font
					(size 0.7 0.7)
					(thickness 0.15)
				)
				(justify left bottom)
			)
		)
		(pad "1" smd rect
			(at -0.653 -0.803 180)
			(size 0.2 0.6)
			(layers "F.Cu" "F.Mask" "F.Paste")
			(net 27 "/USB/USB_3V3")
			(pinfunction "VCCA")
			(pintype "power_in")
		)
		(pad "1" smd rect
			(at -0.425 -0.975 270)
			(size 0.15 0.25)
			(layers "F.Cu" "F.Mask" "F.Paste")
			(net 27 "/USB/USB_3V3")
			(pinfunction "VCCA")
			(pintype "power_in")
		)
		(pad "2" smd rect
			(at -0.653 -0.403 180)
			(size 0.2 0.6)
			(layers "F.Cu" "F.Mask" "F.Paste")
			(net 3 "GND")
			(pinfunction "A1")
			(pintype "tri_state")
		)
		(pad "3" smd rect
			(at -0.653 0 180)
			(size 0.2 0.6)
			(layers "F.Cu" "F.Mask" "F.Paste")
			(net 3 "GND")
			(pinfunction "A2")
			(pintype "tri_state")
		)
		(pad "4" smd rect
			(at -0.653 0.4 180)
			(size 0.2 0.6)
			(layers "F.Cu" "F.Mask" "F.Paste")
			(net 457 "/USB/BDBUS1")
			(pinfunction "A3")
			(pintype "tri_state")
		)
		(pad "5" smd rect
			(at -0.653 0.8 180)
			(size 0.2 0.6)
			(layers "F.Cu" "F.Mask" "F.Paste")
			(net 456 "/USB/BDBUS0")
			(pinfunction "A4")
			(pintype "tri_state")
		)
		(pad "6" smd rect
			(at 0 0.8 180)
			(size 0.6 0.2)
			(layers "F.Cu" "F.Mask" "F.Paste")
			(net 3 "GND")
			(pinfunction "GND")
			(pintype "power_in")
		)
		(pad "7" smd rect
			(at 0.65 0.8 180)
			(size 0.2 0.6)
			(layers "F.Cu" "F.Mask" "F.Paste")
			(net 187 "/Compute module/UART.1.RX")
			(pinfunction "B4")
			(pintype "tri_state")
		)
		(pad "8" smd rect
			(at 0.65 0.4 180)
			(size 0.2 0.6)
			(layers "F.Cu" "F.Mask" "F.Paste")
			(net 186 "/Compute module/UART.1.TX")
			(pinfunction "B3")
			(pintype "tri_state")
		)
		(pad "9" smd rect
			(at 0.65 0 180)
			(size 0.2 0.6)
			(layers "F.Cu" "F.Mask" "F.Paste")
			(net 3 "GND")
			(pinfunction "B2")
			(pintype "tri_state")
		)
		(pad "10" smd rect
			(at 0.65 -0.403 180)
			(size 0.2 0.6)
			(layers "F.Cu" "F.Mask" "F.Paste")
			(net 3 "GND")
			(pinfunction "B1")
			(pintype "tri_state")
		)
		(pad "11" smd rect
			(at 0.65 -0.803 180)
			(size 0.2 0.6)
			(layers "F.Cu" "F.Mask" "F.Paste")
			(net 9 "+3V3")
			(pinfunction "VCCB")
			(pintype "power_in")
		)
		(pad "12" smd rect
			(at 0 -0.803 180)
			(size 0.6 0.2)
			(layers "F.Cu" "F.Mask" "F.Paste")
			(net 455 "Net-(Q905-D)")
			(pinfunction "OE")
			(pintype "input")
		)
	)
	(footprint "antmicro-footprints:TP_SMD_0.75mm"
		(layer "F.Cu")
		(at 97.697962 122.434)
		(property "Reference" "TP912"
			(at 25.935 26.15 0)
			(layer "F.SilkS")
			(effects
				(font
					(size 0.7 0.7)
					(thickness 0.15)
				)
				(justify left bottom)
			)
		)
		(property "Value" "TP_0.75mm_SMD"
			(at 0 1.2 0)
			(layer "F.Fab")
			(effects
				(font
					(size 0.7 0.7)
					(thickness 0.15)
				)
				(justify left bottom)
			)
		)
		(property "MPN" ""
			(at 0 0 0)
			(unlocked yes)
			(layer "F.Fab")
			(hide yes)
			(effects
				(font
					(size 1 1)
					(thickness 0.15)
				)
			)
		)
		(property "Manufacturer" ""
			(at 0 0 0)
			(unlocked yes)
			(layer "F.Fab")
			(hide yes)
			(effects
				(font
					(size 1 1)
					(thickness 0.15)
				)
			)
		)
		(property "Author" "Antmicro"
			(at 0 0 0)
			(unlocked yes)
			(layer "F.Fab")
			(hide yes)
			(effects
				(font
					(size 1 1)
					(thickness 0.15)
				)
			)
		)
		(property "License" "Apache-2.0"
			(at 0 0 0)
			(unlocked yes)
			(layer "F.Fab")
			(hide yes)
			(effects
				(font
					(size 1 1)
					(thickness 0.15)
				)
			)
		)
		(sheetname "/USB/")
		(sheetfile "usb.kicad_sch")
		(attr exclude_from_pos_files exclude_from_bom)
		(fp_circle
			(center 0 0)
			(end 0.475 0)
			(stroke
				(width 0.05)
				(type default)
			)
			(fill no)
			(layer "F.CrtYd")
		)
		(fp_text user "Author: Antmicro"
			(at -0.4 3.901 0)
			(layer "F.Fab")
			(effects
				(font
					(size 0.7 0.7)
					(thickness 0.15)
				)
				(justify left bottom)
			)
		)
		(fp_text user "${REFERENCE}"
			(at -0.4 2.7 0)
			(layer "F.Fab")
			(effects
				(font
					(size 0.7 0.7)
					(thickness 0.15)
				)
				(justify left bottom)
			)
		)
		(fp_text user "License: Apache-2.0"
			(at -0.4 5.101 0)
			(layer "F.Fab")
			(effects
				(font
					(size 0.7 0.7)
					(thickness 0.15)
				)
				(justify left bottom)
			)
		)
		(pad "1" smd circle
			(at 0 0)
			(size 0.75 0.75)
			(layers "F.Cu" "F.Mask")
			(net 437 "Net-(U906-OUT2)")
			(pinfunction "1")
			(pintype "passive")
		)
	)
)
